# S9S_MB_2U (Grand Teton) — schematic netlist excerpt (pin names and nets, part order shuffled) for the footprints in the layout excerpt that follows; sources: Cadence DE-HDL packaged netlist, KiCad conversion of 03242023_DA0F0TMBIJ0_F0T_Motherboard_J_brd_V01_OCP.brd

R4589  Q_RES  10K 1% CHIP  pkg 0402LF  page 195 : A = P3V3_AUX ; B = FAB_BMC_REV_ID1
C228  Q_CAP  10UF 6.3V 20% X6S  pkg C0402  page 77 : A = PVCCIN_CPU1 ; B = GND

(kicad_pcb
	(version 20260206)
	(generator "pcbnew")
	(generator_version "10.0")
	(general
		(thickness 1.6)
		(legacy_teardrops no)
	)
	(paper "A4")
	(title_block
		(title "03242023_DA0F0TMBIJ0_F0T_Motherboard_J_brd_V01_OCP.brd")
		(comment 1 "Grand Teton / footprints 788-789 of 6105")
	)
	(layers
		(0 "F.Cu" signal "TOP")
		(4 "In1.Cu" signal "GND")
		(6 "In2.Cu" signal "IN1")
		(8 "In3.Cu" signal "GND1")
		(10 "In4.Cu" signal "IN2")
		(12 "In5.Cu" signal "GND2")
		(14 "In6.Cu" signal "IN3")
		(16 "In7.Cu" signal "GND3")
		(18 "In8.Cu" signal "VCC")
		(20 "In9.Cu" signal "VCC1")
		(22 "In10.Cu" signal "GND4")
		(24 "In11.Cu" signal "IN4")
		(26 "In12.Cu" signal "GND5")
		(28 "In13.Cu" signal "IN5")
		(30 "In14.Cu" signal "GND6")
		(32 "In15.Cu" signal "IN6")
		(34 "In16.Cu" signal "GND7")
		(2 "B.Cu" signal "BOTTOM")
		(9 "F.Adhes" user "F.Adhesive")
		(11 "B.Adhes" user "B.Adhesive")
		(13 "F.Paste" user "Package Geometry/Pastemask Top")
		(15 "B.Paste" user "Package Geometry/Pastemask Bottom")
		(5 "F.SilkS" user "Ref Des/Silkscreen Top")
		(7 "B.SilkS" user "Ref Des/Silkscreen Bottom")
		(1 "F.Mask" user "Board Geometry/Soldermask Top")
		(3 "B.Mask" user "Board Geometry/Soldermask Bottom")
		(17 "Dwgs.User" user "User.Drawings")
		(19 "Cmts.User" user "User.Comments")
		(21 "Eco1.User" user "User.Eco1")
		(23 "Eco2.User" user "User.Eco2")
		(25 "Edge.Cuts" user "Board Geometry/Outline")
		(27 "Margin" user)
		(31 "F.CrtYd" user "Package Geometry/Place Bound Top")
		(29 "B.CrtYd" user "Package Geometry/Place Bound Bottom")
		(35 "F.Fab" user "Ref Des/Assembly Top")
		(33 "B.Fab" user "Ref Des/Assembly Bottom")
	)
	(footprint ""
		(layer "F.Cu")
		(at 118.542816 -258.72694 90)
		(property "Reference" "C228"
			(at 0 0 90)
			(layer "F.SilkS")
			(hide yes)
			(effects
				(font
					(size 1.27 1.27)
				)
			)
		)
		(property "Value" ""
			(at 0 0 90)
			(layer "F.Fab")
			(effects
				(font
					(size 1.27 1.27)
				)
			)
		)
		(duplicate_pad_numbers_are_jumpers no)
		(fp_line
			(start 0.7874 -0.4064)
			(end 0.7874 0.4064)
			(stroke
				(width 0.1524)
				(type default)
			)
			(layer "F.SilkS")
		)
		(fp_line
			(start -0.7874 -0.4064)
			(end 0.7874 -0.4064)
			(stroke
				(width 0.1524)
				(type default)
			)
			(layer "F.SilkS")
		)
		(fp_line
			(start 0.7874 0.4064)
			(end -0.7874 0.4064)
			(stroke
				(width 0.1524)
				(type default)
			)
			(layer "F.SilkS")
		)
		(fp_line
			(start -0.7874 0.4064)
			(end -0.7874 -0.4064)
			(stroke
				(width 0.1524)
				(type default)
			)
			(layer "F.SilkS")
		)
		(fp_line
			(start -0.12065 -0.305054)
			(end -0.12065 -0.2794)
			(stroke
				(width 0.1)
				(type default)
			)
			(layer "F.Fab")
		)
		(fp_line
			(start -0.67945 -0.305054)
			(end -0.12065 -0.305054)
			(stroke
				(width 0.1)
				(type default)
			)
			(layer "F.Fab")
		)
		(fp_line
			(start 0.67945 -0.3048)
			(end 0.67945 0.3048)
			(stroke
				(width 0.1)
				(type default)
			)
			(layer "F.Fab")
		)
		(fp_line
			(start 0.12065 -0.3048)
			(end 0.67945 -0.3048)
			(stroke
				(width 0.1)
				(type default)
			)
			(layer "F.Fab")
		)
		(fp_line
			(start 0.12065 -0.2794)
			(end 0.12065 -0.3048)
			(stroke
				(width 0.1)
				(type default)
			)
			(layer "F.Fab")
		)
		(fp_line
			(start -0.12065 -0.2794)
			(end 0.12065 -0.2794)
			(stroke
				(width 0.1)
				(type default)
			)
			(layer "F.Fab")
		)
		(fp_line
			(start 0.120396 0.2794)
			(end -0.12065 0.2794)
			(stroke
				(width 0.1)
				(type default)
			)
			(layer "F.Fab")
		)
		(fp_line
			(start -0.12065 0.2794)
			(end -0.12065 0.3048)
			(stroke
				(width 0.1)
				(type default)
			)
			(layer "F.Fab")
		)
		(fp_line
			(start 0.67945 0.3048)
			(end 0.120396 0.3048)
			(stroke
				(width 0.1)
				(type default)
			)
			(layer "F.Fab")
		)
		(fp_line
			(start 0.120396 0.3048)
			(end 0.120396 0.2794)
			(stroke
				(width 0.1)
				(type default)
			)
			(layer "F.Fab")
		)
		(fp_line
			(start -0.12065 0.3048)
			(end -0.67945 0.3048)
			(stroke
				(width 0.1)
				(type default)
			)
			(layer "F.Fab")
		)
		(fp_line
			(start -0.67945 0.3048)
			(end -0.67945 -0.305054)
			(stroke
				(width 0.1)
				(type default)
			)
			(layer "F.Fab")
		)
		(pad "1" smd circle
			(at -0.40005 0 90)
			(size 0 0)
			(layers "F.Cu" "F.Mask" "F.Paste")
			(net "PVCCIN_CPU1")
		)
		(pad "2" smd circle
			(at 0.40005 0 90)
			(size 0 0)
			(layers "F.Cu" "F.Mask" "F.Paste")
			(net "GND")
		)
	)
	(footprint ""
		(layer "F.Cu")
		(at 181.7624 -93.538548 90)
		(property "Reference" "R4589"
			(at 0 0 90)
			(layer "F.SilkS")
			(hide yes)
			(effects
				(font
					(size 1.27 1.27)
				)
			)
		)
		(property "Value" ""
			(at 0 0 90)
			(layer "F.Fab")
			(effects
				(font
					(size 1.27 1.27)
				)
			)
		)
		(duplicate_pad_numbers_are_jumpers no)
		(fp_line
			(start 0.7874 -0.4064)
			(end 0.7874 0.4064)
			(stroke
				(width 0.1524)
				(type default)
			)
			(layer "F.SilkS")
		)
		(fp_line
			(start -0.7874 -0.4064)
			(end 0.7874 -0.4064)
			(stroke
				(width 0.1524)
				(type default)
			)
			(layer "F.SilkS")
		)
		(fp_line
			(start 0.7874 0.4064)
			(end -0.7874 0.4064)
			(stroke
				(width 0.1524)
				(type default)
			)
			(layer "F.SilkS")
		)
		(fp_line
			(start -0.7874 0.4064)
			(end -0.7874 -0.4064)
			(stroke
				(width 0.1524)
				(type default)
			)
			(layer "F.SilkS")
		)
		(fp_line
			(start -0.12065 -0.305054)
			(end -0.12065 -0.2794)
			(stroke
				(width 0.1)
				(type default)
			)
			(layer "F.Fab")
		)
		(fp_line
			(start -0.67945 -0.305054)
			(end -0.12065 -0.305054)
			(stroke
				(width 0.1)
				(type default)
			)
			(layer "F.Fab")
		)
		(fp_line
			(start 0.67945 -0.3048)
			(end 0.67945 0.3048)
			(stroke
				(width 0.1)
				(type default)
			)
			(layer "F.Fab")
		)
		(fp_line
			(start 0.12065 -0.3048)
			(end 0.67945 -0.3048)
			(stroke
				(width 0.1)
				(type default)
			)
			(layer "F.Fab")
		)
		(fp_line
			(start 0.12065 -0.2794)
			(end 0.12065 -0.3048)
			(stroke
				(width 0.1)
				(type default)
			)
			(layer "F.Fab")
		)
		(fp_line
			(start -0.12065 -0.2794)
			(end 0.12065 -0.2794)
			(stroke
				(width 0.1)
				(type default)
			)
			(layer "F.Fab")
		)
		(fp_line
			(start 0.120396 0.2794)
			(end -0.12065 0.2794)
			(stroke
				(width 0.1)
				(type default)
			)
			(layer "F.Fab")
		)
		(fp_line
			(start -0.12065 0.2794)
			(end -0.12065 0.3048)
			(stroke
				(width 0.1)
				(type default)
			)
			(layer "F.Fab")
		)
		(fp_line
			(start 0.67945 0.3048)
			(end 0.120396 0.3048)
			(stroke
				(width 0.1)
				(type default)
			)
			(layer "F.Fab")
		)
		(fp_line
			(start 0.120396 0.3048)
			(end 0.120396 0.2794)
			(stroke
				(width 0.1)
				(type default)
			)
			(layer "F.Fab")
		)
		(fp_line
			(start -0.12065 0.3048)
			(end -0.67945 0.3048)
			(stroke
				(width 0.1)
				(type default)
			)
			(layer "F.Fab")
		)
		(fp_line
			(start -0.67945 0.3048)
			(end -0.67945 -0.305054)
			(stroke
				(width 0.1)
				(type default)
			)
			(layer "F.Fab")
		)
		(pad "1" smd rect
			(at -0.40005 0 270)
			(size 0.4572 0.508)
			(layers "F.Cu" "F.Mask" "F.Paste")
			(net "P3V3_AUX")
		)
		(pad "2" smd rect
			(at 0.40005 0 270)
			(size 0.4572 0.508)
			(layers "F.Cu" "F.Mask" "F.Paste")
			(net "FAB_BMC_REV_ID1")
		)
	)
)
